%FSTAX25Y25*%
%MOIN*%
%SFA1B1*%

%IPPOS*%
%ADD9500C,0.008000*%
%ADD9501C,0.016000*%
%ADD9502C,0.021660*%
%ADD9503C,0.028000*%
%ADD9504C,0.029920*%
%ADD9505C,0.035430*%
%ADD9506C,0.050000*%
%ADD9507C,0.060000*%
%ADD9508C,0.068000*%
%ADD9509C,0.118110*%
%ADD9510C,0.122000*%
%ADD9511C,0.065980*%
%ADD9512C,0.125200*%
%LNtimecard-dc-beta-v1-1*%
%LPD*%
G54D9500*
X0349705Y0064173D03*
X0349853Y0068206D03*
X028937Y0079528D03*
X0286221D03*
X0282677D03*
X0279921D03*
X0275984D03*
X0273228D03*
X0269291D03*
X0266535D03*
X0262598D03*
X0259842D03*
X0260668Y009319D03*
X0262205Y0097638D03*
X0264961D03*
X026811D03*
X0270866D03*
X0274016D03*
X0276772D03*
X0279921D03*
X0282677D03*
X0290551Y0093701D03*
X0290158Y011063D03*
X0285039D03*
X027874D03*
X0272835D03*
X0266535D03*
X0261024D03*
X0251181Y0110591D03*
X0240945Y011063D03*
X0231102D03*
X0231496Y0093307D03*
X0241339D03*
X0251575D03*
X0251181Y0040551D03*
X0246988Y0041099D03*
X0238976Y0040551D03*
X0235039D03*
X0241339Y0027953D03*
X0244488D03*
X0244706Y0024259D03*
X0254606Y0024484D03*
X0257874Y0027953D03*
X0261024D03*
X0263687Y0024791D03*
X0274882Y0028231D03*
X0277953Y0027953D03*
X0279999Y0025197D03*
X0287828Y002496D03*
X0290549Y0027951D03*
X0293701Y0027953D03*
X0295747Y0025197D03*
X0309744D03*
X0301969Y0040551D03*
X0298046Y0040915D03*
X0285433Y0040551D03*
X0282198Y0040785D03*
X0270472Y0040551D03*
X0266535D03*
X0230984Y0024606D03*
X0215158Y0025591D03*
Y002874D03*
X0211221D03*
Y0025591D03*
X0207677D03*
Y002874D03*
X0203484Y0024606D03*
X0191614Y0024476D03*
X0187205Y0025591D03*
X0185236D03*
X0183268D03*
Y002874D03*
X0185236D03*
X0187205D03*
X0207087Y0037795D03*
X0209646Y0054134D03*
Y0056102D03*
X0211614D03*
Y0054134D03*
X0213583D03*
Y0056102D03*
X0216535Y0068898D03*
X0201772Y0076772D03*
X0119587Y0091437D03*
X0112205Y0117126D03*
X0101181Y0110433D03*
X0052789Y0102806D03*
X0045276Y0112205D03*
Y0121063D03*
X0052689Y0079006D03*
Y0131406D03*
X0052589Y0155106D03*
X0052689Y0183906D03*
Y0207306D03*
X004626Y0218504D03*
Y0227362D03*
X0052689Y0236506D03*
X0052601Y0259389D03*
X0120079Y0253937D03*
X011998Y0250197D03*
X011811Y0237205D03*
X0107283Y0231299D03*
X0120079Y0200787D03*
X0119685Y0196752D03*
X011811Y0184055D03*
X0107283Y0177165D03*
Y0169291D03*
X0101378Y0161417D03*
X011939Y0143504D03*
X0134843Y0151575D03*
X0149606D03*
X0167184Y0149606D03*
X0171884D03*
X0171684Y0139906D03*
X0167184D03*
X0167084Y0159506D03*
X0171484D03*
X0172184Y0168571D03*
X0167084D03*
X0167184Y0179206D03*
X0171884D03*
X0172184Y0189006D03*
X0167584Y0189106D03*
X0167484Y0198906D03*
X0172184D03*
X0164961Y023002D03*
X0166437Y0233661D03*
X0184144Y0210148D03*
X0184429Y0207604D03*
X0188944Y0151607D03*
X0231004Y0229035D03*
X0233563D03*
X0240613Y0229269D03*
X0243307Y0229134D03*
X0245674Y0228738D03*
X0248107Y0229134D03*
X0252953D03*
X0255906D03*
X0259547Y0229035D03*
X0262598Y0229134D03*
X0266437D03*
X0272638Y0229331D03*
X0280512D03*
X0286024Y0229232D03*
X029813D03*
X0293307Y021752D03*
X0289923D03*
X0288059Y0241869D03*
Y0246457D03*
X0278543D03*
X0278248Y0241831D03*
X0268437D03*
X0268701Y0246457D03*
X025889D03*
Y0242126D03*
X0248819Y0241831D03*
X024941Y0246457D03*
X0239173D03*
X0240158Y0242126D03*
X023002Y024187D03*
X0229035Y0246555D03*
X0228051Y0260039D03*
X0237205Y0267717D03*
X024311Y0267748D03*
X0244882Y0260236D03*
X0247638D03*
X0258858Y0262795D03*
X0290059Y026063D03*
X0293069Y0257983D03*
X0298031Y0260531D03*
X0312894Y0273721D03*
X0331693Y0269685D03*
X0331802Y0166952D03*
X0354331Y0171291D03*
X0360236D03*
Y0181102D03*
X0354331D03*
Y0190945D03*
X0360236D03*
Y0200787D03*
X0354331D03*
X0338583Y0202756D03*
Y0204724D03*
Y0206693D03*
Y0208661D03*
X0373031D03*
Y0206693D03*
Y0204724D03*
Y0202756D03*
Y0188976D03*
Y0180118D03*
Y0177165D03*
Y0167291D03*
X0386372Y0163466D03*
X0386433Y0160893D03*
X0386458Y0157787D03*
X0401575Y015748D03*
Y0160433D03*
Y0162833D03*
Y0165354D03*
Y0168307D03*
X0401533Y0172321D03*
X0401461Y0175652D03*
X0401575Y017815D03*
X0386371D03*
X0397899Y0165616D03*
X0360236Y0161417D03*
X0354331D03*
Y0151575D03*
X0360236D03*
Y0141732D03*
X0354331D03*
X0341142Y0142421D03*
Y0139272D03*
X0341283Y0136314D03*
X0341397Y0133917D03*
X0343504Y0269685D03*
Y027559D03*
X0357185Y0272736D03*
X0362156Y0278592D03*
X0492913Y0274803D03*
X0490158Y0270638D03*
X0512795Y0279528D03*
X0523228Y0273622D03*
X0525591Y0271654D03*
X0564921Y0275551D03*
X0564961Y0280512D03*
X0612992Y0276772D03*
X0645084Y0274016D03*
X0645182Y0267323D03*
X0645276Y026063D03*
X0645084Y0253543D03*
Y0246263D03*
X0627484Y0239106D03*
X0600394Y0243021D03*
X0604884Y0217106D03*
X0622047Y0206693D03*
Y0200787D03*
Y0198819D03*
X0620079D03*
Y0200787D03*
Y019685D03*
X0622047D03*
X0639584Y0211106D03*
X0597441Y0145669D03*
X0595472D03*
Y0143701D03*
X0597441D03*
Y0141732D03*
X0595472D03*
X0662884Y0137206D03*
X065878Y0152931D03*
X0659449Y0161024D03*
Y0167323D03*
Y0172047D03*
Y0177559D03*
X0669478Y018309D03*
X0669984Y0188106D03*
X0697884Y0183071D03*
X0694984Y0209506D03*
X065748Y0208661D03*
X0660784Y0217606D03*
X0663171Y0314014D03*
Y0315982D03*
X066514D03*
X0667108D03*
Y0314014D03*
X066514D03*
X0636221Y0295276D03*
X0627559D03*
X0570866Y0285433D03*
X0564921Y0290394D03*
X0525591Y0298228D03*
X0519685D03*
X0523228Y0281496D03*
X0512795Y028248D03*
X0505905Y0283465D03*
X05Y0295276D03*
X0505905Y0416339D03*
X0449803Y028937D03*
Y0284449D03*
X0371477Y0289616D03*
X0362205Y0281496D03*
X0366142Y0303118D03*
X0356299D03*
X0350394D03*
X0329918Y0292362D03*
X0324803Y0293276D03*
X0320866Y0293307D03*
X0311024Y0285433D03*
Y0283465D03*
Y0281496D03*
X030115Y0291307D03*
X0294341Y0291289D03*
X0279528Y0284449D03*
X0249938Y0283527D03*
X0261811Y0309055D03*
X0270669Y0309087D03*
X0276772Y0320079D03*
X0286417Y0327756D03*
X0302165Y0332677D03*
X0304134Y0339567D03*
X0271654Y0346457D03*
Y0354331D03*
Y0362205D03*
X0238189D03*
Y0354331D03*
Y0346457D03*
X0217488Y0357695D03*
X021752Y0363189D03*
X0199803D03*
Y0357283D03*
X0202756Y0409449D03*
X0181102D03*
X0173228D03*
X0160433D03*
X0124397Y0401594D03*
X010423Y040146D03*
X0084064Y0401327D03*
X0063897Y0401294D03*
X0064961Y0430118D03*
X0084646D03*
X0104331D03*
X0125D03*
X0163992Y0362811D03*
X0163957Y035748D03*
X0181727D03*
X0181794Y0362897D03*
G54D9501*
X0619685Y0248425D03*
X0683858Y0164961D03*
G54D9502*
X0220275Y0095846D03*
X0299015D03*
X0169644Y013097D03*
Y020971D03*
X0220274Y024384D03*
X0299014D03*
X0357136Y0209705D03*
Y0130965D03*
G54D9503*
X0370669Y0072933D03*
G54D9504*
X025503Y034252D03*
Y0358268D03*
G54D9505*
X0513622Y0426181D03*
X0523622D03*
X0533622D03*
X0543622D03*
G54D9506*
X055873Y0087992D03*
X0398888D03*
Y0247835D03*
X0407156Y0258465D03*
X0418966D03*
X0430778D03*
X055873Y0247835D03*
Y0167913D03*
G54D9507*
X0019984Y0090606D03*
Y0143106D03*
Y0195606D03*
Y0248106D03*
G54D9508*
X0029984Y0080606D03*
Y0100606D03*
X0009984D03*
Y0080606D03*
Y0133106D03*
Y0153106D03*
Y0185606D03*
Y0205606D03*
Y0238106D03*
Y0258106D03*
X0029984D03*
Y0238106D03*
Y0205606D03*
Y0185606D03*
Y0153106D03*
Y0133106D03*
G54D9509*
X0361755Y0091615D03*
X0165255D03*
X0165155Y0248616D03*
X0361755D03*
G54D9510*
X0482313Y0317303D03*
Y0419665D03*
X0244124D03*
Y0317303D03*
G54D9511*
X019661Y040861D03*
X016661D03*
G54D9512*
X0028543Y0036811D03*
Y0415206D03*
M02*